(kicad_pcb
	(version 20241229)
	(generator "pcbnew")
	(generator_version "9.0")
	(general
		(thickness 1.6642)
		(legacy_teardrops no)
	)
	(paper "A3")
	(title_block
		(title "PolarFire SoM")
		(date "2025-07-22")
		(rev "1.1.4")
		(company "Antmicro Ltd")
		(comment 1 "www.antmicro.com")
		(comment 9 "footprint 35 of 470 (U16), pads 1-61 of 80")
	)
	(layers
		(0 "F.Cu" mixed)
		(4 "In1.Cu" power)
		(6 "In2.Cu" signal)
		(8 "In3.Cu" power)
		(10 "In4.Cu" signal)
		(12 "In5.Cu" power)
		(14 "In6.Cu" power)
		(16 "In7.Cu" signal)
		(18 "In8.Cu" power)
		(20 "In9.Cu" signal)
		(22 "In10.Cu" power)
		(24 "In11.Cu" signal)
		(26 "In12.Cu" signal)
		(2 "B.Cu" mixed)
		(9 "F.Adhes" user "F.Adhesive")
		(11 "B.Adhes" user "B.Adhesive")
		(13 "F.Paste" user)
		(15 "B.Paste" user)
		(5 "F.SilkS" user "F.Silkscreen")
		(7 "B.SilkS" user "B.Silkscreen")
		(1 "F.Mask" user)
		(3 "B.Mask" user)
		(17 "Dwgs.User" user "User.Drawings")
		(19 "Cmts.User" user "User.Comments")
		(21 "Eco1.User" user "User.Eco1")
		(23 "Eco2.User" user "User.Eco2")
		(25 "Edge.Cuts" user)
		(27 "Margin" user)
		(31 "F.CrtYd" user "F.Courtyard")
		(29 "B.CrtYd" user "B.Courtyard")
		(35 "F.Fab" user)
		(33 "B.Fab" user)
	)
	(footprint "antmicro-footprints:BGA-80_7x7mm_Layout10x10_P0.65mm"
		(layer "F.Cu")
		(at 203.374 147.076 180)
		(property "Reference" "U16"
			(at 1.564 -4.684 0)
			(layer "F.SilkS")
			(effects
				(font
					(size 0.7 0.7)
					(thickness 0.15)
				)
				(justify right bottom)
			)
		)
		(property "Value" "CrossLink_LIF-MD6000-6JMG80I"
			(at 0 4.65 0)
			(layer "F.Fab")
			(hide yes)
			(effects
				(font
					(size 0.7 0.7)
					(thickness 0.15)
				)
				(justify right bottom)
			)
		)
		(property "Datasheet" "https://www.latticesemi.com/view_document?document_id=51662"
			(at 0 0 180)
			(layer "F.Fab")
			(hide yes)
			(effects
				(font
					(size 1.27 1.27)
					(thickness 0.15)
				)
			)
		)
		(property "Description" "FPGA, CrossLink, PLL37 I/O, 400 MHz, 5936 Cells, 1.14 V to 1.26 V, CTFBGA-80"
			(at 0 0 180)
			(layer "F.Fab")
			(hide yes)
			(effects
				(font
					(size 1.27 1.27)
					(thickness 0.15)
				)
			)
		)
		(property "Author" "Antmicro"
			(at 406.748 294.152 0)
			(layer "F.Fab")
			(hide yes)
			(effects
				(font
					(size 1 1)
					(thickness 0.15)
				)
			)
		)
		(property "License" "Apache-2.0"
			(at 406.748 294.152 0)
			(layer "F.Fab")
			(hide yes)
			(effects
				(font
					(size 1 1)
					(thickness 0.15)
				)
			)
		)
		(property "MPN" "LIF-MD6000-6JMG80I"
			(at 406.748 294.152 0)
			(layer "F.Fab")
			(hide yes)
			(effects
				(font
					(size 1 1)
					(thickness 0.15)
				)
			)
		)
		(property "Manufacturer" "Lattice Semiconductor"
			(at 406.748 294.152 0)
			(layer "F.Fab")
			(hide yes)
			(effects
				(font
					(size 1 1)
					(thickness 0.15)
				)
			)
		)
		(sheetname "/MIPI CrossLink/")
		(sheetfile "crosslink.kicad_sch")
		(attr smd)
		(pad "A1" smd circle
			(at -2.925 -2.925 180)
			(size 0.35 0.35)
			(layers "F.Cu" "F.Mask" "F.Paste")
			(net 197 "/Bottom Connector/DSI1.D2_N")
			(pinfunction "DPHY1_DN2")
			(pintype "bidirectional")
			(solder_mask_margin -0.025)
			(solder_paste_margin -0.025)
		)
		(pad "A2" smd circle
			(at -2.275 -2.925 180)
			(size 0.35 0.35)
			(layers "F.Cu" "F.Mask" "F.Paste")
			(net 146 "/Bottom Connector/DSI1.D0_N")
			(pinfunction "DPHY1_DN0")
			(pintype "bidirectional")
			(solder_mask_margin -0.025)
			(solder_paste_margin -0.025)
		)
		(pad "A3" smd circle
			(at -1.625 -2.925 180)
			(size 0.35 0.35)
			(layers "F.Cu" "F.Mask" "F.Paste")
			(net 162 "/Bottom Connector/DSI1.C_N")
			(pinfunction "DPHY1_CKN")
			(pintype "bidirectional")
			(solder_mask_margin -0.025)
			(solder_paste_margin -0.025)
		)
		(pad "A4" smd circle
			(at -0.975 -2.925 180)
			(size 0.35 0.35)
			(layers "F.Cu" "F.Mask" "F.Paste")
			(net 158 "/Bottom Connector/DSI1.D1_N")
			(pinfunction "DPHY1_DN1")
			(pintype "bidirectional")
			(solder_mask_margin -0.025)
			(solder_paste_margin -0.025)
		)
		(pad "A5" smd circle
			(at -0.325 -2.925 180)
			(size 0.35 0.35)
			(layers "F.Cu" "F.Mask" "F.Paste")
			(net 198 "/Bottom Connector/DSI1.D3_N")
			(pinfunction "DPHY1_DN3")
			(pintype "bidirectional")
			(solder_mask_margin -0.025)
			(solder_paste_margin -0.025)
		)
		(pad "A6" smd circle
			(at 0.325 -2.925 180)
			(size 0.35 0.35)
			(layers "F.Cu" "F.Mask" "F.Paste")
			(net 112 "/Bottom Connector/CAM1.D2_N")
			(pinfunction "DPHY0_DN2")
			(pintype "bidirectional")
			(solder_mask_margin -0.025)
			(solder_paste_margin -0.025)
		)
		(pad "A7" smd circle
			(at 0.975 -2.925 180)
			(size 0.35 0.35)
			(layers "F.Cu" "F.Mask" "F.Paste")
			(net 99 "/Bottom Connector/CAM1.D0_N")
			(pinfunction "DPHY0_DN0")
			(pintype "bidirectional")
			(solder_mask_margin -0.025)
			(solder_paste_margin -0.025)
		)
		(pad "A8" smd circle
			(at 1.625 -2.925 180)
			(size 0.35 0.35)
			(layers "F.Cu" "F.Mask" "F.Paste")
			(net 108 "/Bottom Connector/CAM1.C_N")
			(pinfunction "DPHY0_CKN")
			(pintype "bidirectional")
			(solder_mask_margin -0.025)
			(solder_paste_margin -0.025)
		)
		(pad "A9" smd circle
			(at 2.275 -2.925 180)
			(size 0.35 0.35)
			(layers "F.Cu" "F.Mask" "F.Paste")
			(net 106 "/Bottom Connector/CAM1.D1_N")
			(pinfunction "DPHY0_DN1")
			(pintype "bidirectional")
			(solder_mask_margin -0.025)
			(solder_paste_margin -0.025)
		)
		(pad "A10" smd circle
			(at 2.925 -2.925 180)
			(size 0.35 0.35)
			(layers "F.Cu" "F.Mask" "F.Paste")
			(net 116 "/Bottom Connector/CAM1.D3_N")
			(pinfunction "DPHY0_DN3")
			(pintype "bidirectional")
			(solder_mask_margin -0.025)
			(solder_paste_margin -0.025)
		)
		(pad "B1" smd circle
			(at -2.925 -2.275 180)
			(size 0.35 0.35)
			(layers "F.Cu" "F.Mask" "F.Paste")
			(net 199 "/Bottom Connector/DSI1.D2_P")
			(pinfunction "DPHY1_DP2")
			(pintype "bidirectional")
			(solder_mask_margin -0.025)
			(solder_paste_margin -0.025)
		)
		(pad "B2" smd circle
			(at -2.275 -2.275 180)
			(size 0.35 0.35)
			(layers "F.Cu" "F.Mask" "F.Paste")
			(net 156 "/Bottom Connector/DSI1.D0_P")
			(pinfunction "DPHY1_DP0")
			(pintype "bidirectional")
			(solder_mask_margin -0.025)
			(solder_paste_margin -0.025)
		)
		(pad "B3" smd circle
			(at -1.625 -2.275 180)
			(size 0.35 0.35)
			(layers "F.Cu" "F.Mask" "F.Paste")
			(net 195 "/Bottom Connector/DSI1.C_P")
			(pinfunction "DPHY1_CKP")
			(pintype "bidirectional")
			(solder_mask_margin -0.025)
			(solder_paste_margin -0.025)
		)
		(pad "B4" smd circle
			(at -0.975 -2.275 180)
			(size 0.35 0.35)
			(layers "F.Cu" "F.Mask" "F.Paste")
			(net 160 "/Bottom Connector/DSI1.D1_P")
			(pinfunction "DPHY1_DP1")
			(pintype "bidirectional")
			(solder_mask_margin -0.025)
			(solder_paste_margin -0.025)
		)
		(pad "B5" smd circle
			(at -0.325 -2.275 180)
			(size 0.35 0.35)
			(layers "F.Cu" "F.Mask" "F.Paste")
			(net 201 "/Bottom Connector/DSI1.D3_P")
			(pinfunction "DPHY1_DP3")
			(pintype "bidirectional")
			(solder_mask_margin -0.025)
			(solder_paste_margin -0.025)
		)
		(pad "B6" smd circle
			(at 0.325 -2.275 180)
			(size 0.35 0.35)
			(layers "F.Cu" "F.Mask" "F.Paste")
			(net 114 "/Bottom Connector/CAM1.D2_P")
			(pinfunction "DPHY0_DP2")
			(pintype "bidirectional")
			(solder_mask_margin -0.025)
			(solder_paste_margin -0.025)
		)
		(pad "B7" smd circle
			(at 0.975 -2.275 180)
			(size 0.35 0.35)
			(layers "F.Cu" "F.Mask" "F.Paste")
			(net 104 "/Bottom Connector/CAM1.D0_P")
			(pinfunction "DPHY0_DP0")
			(pintype "bidirectional")
			(solder_mask_margin -0.025)
			(solder_paste_margin -0.025)
		)
		(pad "B8" smd circle
			(at 1.625 -2.275 180)
			(size 0.35 0.35)
			(layers "F.Cu" "F.Mask" "F.Paste")
			(net 110 "/Bottom Connector/CAM1.C_P")
			(pinfunction "DPHY0_CKP")
			(pintype "bidirectional")
			(solder_mask_margin -0.025)
			(solder_paste_margin -0.025)
		)
		(pad "B9" smd circle
			(at 2.275 -2.275 180)
			(size 0.35 0.35)
			(layers "F.Cu" "F.Mask" "F.Paste")
			(net 107 "/Bottom Connector/CAM1.D1_P")
			(pinfunction "DPHY0_DP1")
			(pintype "bidirectional")
			(solder_mask_margin -0.025)
			(solder_paste_margin -0.025)
		)
		(pad "B10" smd circle
			(at 2.925 -2.275 180)
			(size 0.35 0.35)
			(layers "F.Cu" "F.Mask" "F.Paste")
			(net 119 "/Bottom Connector/CAM1.D3_P")
			(pinfunction "DPHY0_DP3")
			(pintype "bidirectional")
			(solder_mask_margin -0.025)
			(solder_paste_margin -0.025)
		)
		(pad "C1" smd circle
			(at -2.925 -1.625 180)
			(size 0.35 0.35)
			(layers "F.Cu" "F.Mask" "F.Paste")
			(net 417 "GND")
			(pinfunction "GND")
			(pintype "power_in")
			(solder_mask_margin -0.025)
			(solder_paste_margin -0.025)
		)
		(pad "C2" smd circle
			(at -2.275 -1.625 180)
			(size 0.35 0.35)
			(layers "F.Cu" "F.Mask" "F.Paste")
			(net 417 "GND")
			(pinfunction "GNDA_DPHY1")
			(pintype "power_in")
			(solder_mask_margin -0.025)
			(solder_paste_margin -0.025)
		)
		(pad "C9" smd circle
			(at 2.275 -1.625 180)
			(size 0.35 0.35)
			(layers "F.Cu" "F.Mask" "F.Paste")
			(net 417 "GND")
			(pinfunction "GNDA_DPHY0")
			(pintype "power_in")
			(solder_mask_margin -0.025)
			(solder_paste_margin -0.025)
		)
		(pad "C10" smd circle
			(at 2.925 -1.625 180)
			(size 0.35 0.35)
			(layers "F.Cu" "F.Mask" "F.Paste")
			(net 417 "GND")
			(pinfunction "GND")
			(pintype "passive")
			(solder_mask_margin -0.025)
			(solder_paste_margin -0.025)
		)
		(pad "D1" smd circle
			(at -2.925 -0.975 180)
			(size 0.35 0.35)
			(layers "F.Cu" "F.Mask" "F.Paste")
			(net 564 "/FPGA GPIO/Crosslink.SCL")
			(pinfunction "PB48/PCLKT0_1/USER_SCL")
			(pintype "bidirectional")
			(solder_mask_margin -0.025)
			(solder_paste_margin -0.025)
		)
		(pad "D2" smd circle
			(at -2.275 -0.975 180)
			(size 0.35 0.35)
			(layers "F.Cu" "F.Mask" "F.Paste")
			(net 211 "/MIPI CrossLink/CL_VCCPLL_DPHY1")
			(pinfunction "VCCPLL_DPHY1")
			(pintype "power_in")
			(solder_mask_margin -0.025)
			(solder_paste_margin -0.025)
		)
		(pad "D4" smd circle
			(at -0.975 -0.975 180)
			(size 0.35 0.35)
			(layers "F.Cu" "F.Mask" "F.Paste")
			(net 205 "/MIPI CrossLink/CL_VCCA_DPHY1")
			(pinfunction "VCCA_DPHY1")
			(pintype "power_in")
			(solder_mask_margin -0.025)
			(solder_paste_margin -0.025)
		)
		(pad "D5" smd circle
			(at -0.325 -0.975 180)
			(size 0.35 0.35)
			(layers "F.Cu" "F.Mask" "F.Paste")
			(net 103 "2V5_CL")
			(pinfunction "VCCAUX")
			(pintype "power_in")
			(solder_mask_margin -0.025)
			(solder_paste_margin -0.025)
		)
		(pad "D6" smd circle
			(at 0.325 -0.975 180)
			(size 0.35 0.35)
			(layers "F.Cu" "F.Mask" "F.Paste")
			(net 417 "GND")
			(pinfunction "GNDPLL_DPHY_X")
			(pintype "power_in")
			(solder_mask_margin -0.025)
			(solder_paste_margin -0.025)
		)
		(pad "D7" smd circle
			(at 0.975 -0.975 180)
			(size 0.35 0.35)
			(layers "F.Cu" "F.Mask" "F.Paste")
			(net 204 "/MIPI CrossLink/CL_VCCPLL_DPHY0")
			(pinfunction "VCCPLL_DPHY0")
			(pintype "bidirectional")
			(solder_mask_margin -0.025)
			(solder_paste_margin -0.025)
		)
		(pad "D9" smd circle
			(at 2.275 -0.975 180)
			(size 0.35 0.35)
			(layers "F.Cu" "F.Mask" "F.Paste")
			(net 154 "/FPGA HSIO/Crosslink_B2.D4")
			(pinfunction "PB16A/PCLKT2_0")
			(pintype "bidirectional")
			(solder_mask_margin -0.025)
			(solder_paste_margin -0.025)
		)
		(pad "D10" smd circle
			(at 2.925 -0.975 180)
			(size 0.35 0.35)
			(layers "F.Cu" "F.Mask" "F.Paste")
			(net 501 "unconnected-(U16-PB16B{slash}PCLKC2_0-PadD10)")
			(pinfunction "PB16B/PCLKC2_0")
			(pintype "bidirectional+no_connect")
			(solder_mask_margin -0.025)
			(solder_paste_margin -0.025)
		)
		(pad "E1" smd circle
			(at -2.925 -0.325 180)
			(size 0.35 0.35)
			(layers "F.Cu" "F.Mask" "F.Paste")
			(net 327 "/FPGA HSIO/Crosslink_B1.D4")
			(pinfunction "PB34A/GR_PCLK1_0")
			(pintype "input")
			(solder_mask_margin -0.025)
			(solder_paste_margin -0.025)
		)
		(pad "E2" smd circle
			(at -2.275 -0.325 180)
			(size 0.35 0.35)
			(layers "F.Cu" "F.Mask" "F.Paste")
			(net 502 "unconnected-(U16-PB34B-PadE2)")
			(pinfunction "PB34B")
			(pintype "bidirectional+no_connect")
			(solder_mask_margin -0.025)
			(solder_paste_margin -0.025)
		)
		(pad "E4" smd circle
			(at -0.975 -0.325 180)
			(size 0.35 0.35)
			(layers "F.Cu" "F.Mask" "F.Paste")
			(net 176 "/MIPI CrossLink/CL_VCC")
			(pinfunction "VCC")
			(pintype "power_in")
			(solder_mask_margin -0.025)
			(solder_paste_margin -0.025)
		)
		(pad "E5" smd circle
			(at -0.325 -0.325 180)
			(size 0.35 0.35)
			(layers "F.Cu" "F.Mask" "F.Paste")
			(net 417 "GND")
			(pinfunction "GND")
			(pintype "passive")
			(solder_mask_margin -0.025)
			(solder_paste_margin -0.025)
		)
		(pad "E6" smd circle
			(at 0.325 -0.325 180)
			(size 0.35 0.35)
			(layers "F.Cu" "F.Mask" "F.Paste")
			(net 176 "/MIPI CrossLink/CL_VCC")
			(pinfunction "VCC")
			(pintype "passive")
			(solder_mask_margin -0.025)
			(solder_paste_margin -0.025)
		)
		(pad "E7" smd circle
			(at 0.975 -0.325 180)
			(size 0.35 0.35)
			(layers "F.Cu" "F.Mask" "F.Paste")
			(net 203 "/MIPI CrossLink/CL_VCCA_DPHY0")
			(pinfunction "VCCA_DPHY0")
			(pintype "power_in")
			(solder_mask_margin -0.025)
			(solder_paste_margin -0.025)
		)
		(pad "E9" smd circle
			(at 2.275 -0.325 180)
			(size 0.35 0.35)
			(layers "F.Cu" "F.Mask" "F.Paste")
			(net 503 "unconnected-(U16-PB12A{slash}GPLLT2_0-PadE9)")
			(pinfunction "PB12A/GPLLT2_0")
			(pintype "input+no_connect")
			(solder_mask_margin -0.025)
			(solder_paste_margin -0.025)
		)
		(pad "E10" smd circle
			(at 2.925 -0.325 180)
			(size 0.35 0.35)
			(layers "F.Cu" "F.Mask" "F.Paste")
			(net 504 "unconnected-(U16-PB12B{slash}GPLLC2_0-PadE10)")
			(pinfunction "PB12B/GPLLC2_0")
			(pintype "input+no_connect")
			(solder_mask_margin -0.025)
			(solder_paste_margin -0.025)
		)
		(pad "F1" smd circle
			(at -2.925 0.325 180)
			(size 0.35 0.35)
			(layers "F.Cu" "F.Mask" "F.Paste")
			(net 339 "/FPGA HSIO/Crosslink_B1.VSYNC")
			(pinfunction "PB38A")
			(pintype "bidirectional")
			(solder_mask_margin -0.025)
			(solder_paste_margin -0.025)
		)
		(pad "F2" smd circle
			(at -2.275 0.325 180)
			(size 0.35 0.35)
			(layers "F.Cu" "F.Mask" "F.Paste")
			(net 335 "/FPGA HSIO/Crosslink_B1.HSYNC")
			(pinfunction "PB38B")
			(pintype "bidirectional")
			(solder_mask_margin -0.025)
			(solder_paste_margin -0.025)
		)
		(pad "F4" smd circle
			(at -0.975 0.325 180)
			(size 0.35 0.35)
			(layers "F.Cu" "F.Mask" "F.Paste")
			(net 183 "/MIPI CrossLink/CL_VCCIO0")
			(pinfunction "VCCIO0")
			(pintype "power_in")
			(solder_mask_margin -0.025)
			(solder_paste_margin -0.025)
		)
		(pad "F5" smd circle
			(at -0.325 0.325 180)
			(size 0.35 0.35)
			(layers "F.Cu" "F.Mask" "F.Paste")
			(net 185 "/MIPI CrossLink/CL_VCCIO1")
			(pinfunction "VCCIO1")
			(pintype "power_in")
			(solder_mask_margin -0.025)
			(solder_paste_margin -0.025)
		)
		(pad "F6" smd circle
			(at 0.325 0.325 180)
			(size 0.35 0.35)
			(layers "F.Cu" "F.Mask" "F.Paste")
			(net 191 "/MIPI CrossLink/CL_VCCIO2")
			(pinfunction "VCCIO2")
			(pintype "power_in")
			(solder_mask_margin -0.025)
			(solder_paste_margin -0.025)
		)
		(pad "F7" smd circle
			(at 0.975 0.325 180)
			(size 0.35 0.35)
			(layers "F.Cu" "F.Mask" "F.Paste")
			(net 191 "/MIPI CrossLink/CL_VCCIO2")
			(pinfunction "VCCIO2")
			(pintype "passive")
			(solder_mask_margin -0.025)
			(solder_paste_margin -0.025)
		)
		(pad "F9" smd circle
			(at 2.275 0.325 180)
			(size 0.35 0.35)
			(layers "F.Cu" "F.Mask" "F.Paste")
			(net 347 "/FPGA HSIO/Crosslink_B2.VSYNC")
			(pinfunction "PB6A/GR_PCLK2_0")
			(pintype "input")
			(solder_mask_margin -0.025)
			(solder_paste_margin -0.025)
		)
		(pad "F10" smd circle
			(at 2.925 0.325 180)
			(size 0.35 0.35)
			(layers "F.Cu" "F.Mask" "F.Paste")
			(net 338 "/FPGA HSIO/Crosslink_B2.HSYNC")
			(pinfunction "PB6B")
			(pintype "bidirectional")
			(solder_mask_margin -0.025)
			(solder_paste_margin -0.025)
		)
		(pad "G1" smd circle
			(at -2.925 0.975 180)
			(size 0.35 0.35)
			(layers "F.Cu" "F.Mask" "F.Paste")
			(net 346 "/FPGA GPIO/Crosslink.MOSI")
			(pinfunction "PB50/MOSI")
			(pintype "bidirectional")
			(solder_mask_margin -0.025)
			(solder_paste_margin -0.025)
		)
		(pad "G2" smd circle
			(at -2.275 0.975 180)
			(size 0.35 0.35)
			(layers "F.Cu" "F.Mask" "F.Paste")
			(net 417 "GND")
			(pinfunction "GND")
			(pintype "passive")
			(solder_mask_margin -0.025)
			(solder_paste_margin -0.025)
		)
		(pad "G4" smd circle
			(at -0.975 0.975 180)
			(size 0.35 0.35)
			(layers "F.Cu" "F.Mask" "F.Paste")
			(net 185 "/MIPI CrossLink/CL_VCCIO1")
			(pinfunction "VCCIO1")
			(pintype "passive")
			(solder_mask_margin -0.025)
			(solder_paste_margin -0.025)
		)
		(pad "G5" smd circle
			(at -0.325 0.975 180)
			(size 0.35 0.35)
			(layers "F.Cu" "F.Mask" "F.Paste")
			(net 417 "GND")
			(pinfunction "GND")
			(pintype "passive")
			(solder_mask_margin -0.025)
			(solder_paste_margin -0.025)
		)
		(pad "G6" smd circle
			(at 0.325 0.975 180)
			(size 0.35 0.35)
			(layers "F.Cu" "F.Mask" "F.Paste")
			(net 180 "/MIPI CrossLink/CL_VCCGPLL")
			(pinfunction "VCCGPLL")
			(pintype "power_in")
			(solder_mask_margin -0.025)
			(solder_paste_margin -0.025)
		)
		(pad "G7" smd circle
			(at 0.975 0.975 180)
			(size 0.35 0.35)
			(layers "F.Cu" "F.Mask" "F.Paste")
			(net 417 "GND")
			(pinfunction "GNDGPLL")
			(pintype "power_in")
			(solder_mask_margin -0.025)
			(solder_paste_margin -0.025)
		)
		(pad "G9" smd circle
			(at 2.275 0.975 180)
			(size 0.35 0.35)
			(layers "F.Cu" "F.Mask" "F.Paste")
			(net 331 "/FPGA HSIO/Crosslink_B2.PCLK")
			(pinfunction "PB2A")
			(pintype "bidirectional")
			(solder_mask_margin -0.025)
			(solder_paste_margin -0.025)
		)
		(pad "G10" smd circle
			(at 2.925 0.975 180)
			(size 0.35 0.35)
			(layers "F.Cu" "F.Mask" "F.Paste")
			(net 223 "/FPGA HSIO/Crosslink_B2.D0")
			(pinfunction "PB2B")
			(pintype "bidirectional")
			(solder_mask_margin -0.025)
			(solder_paste_margin -0.025)
		)
		(pad "H1" smd circle
			(at -2.925 1.625 180)
			(size 0.35 0.35)
			(layers "F.Cu" "F.Mask" "F.Paste")
			(net 345 "/FPGA GPIO/Crosslink.CS")
			(pinfunction "PB52/SPI_SS/CSN/SCL")
			(pintype "bidirectional")
			(solder_mask_margin -0.025)
			(solder_paste_margin -0.025)
		)
		(pad "H2" smd circle
			(at -2.275 1.625 180)
			(size 0.35 0.35)
			(layers "F.Cu" "F.Mask" "F.Paste")
			(net 289 "~{Crosslink_RESET}")
			(pinfunction "CRESET_B")
			(pintype "input")
			(solder_mask_margin -0.025)
			(solder_paste_margin -0.025)
		)
		(pad "H9" smd circle
			(at 2.275 1.625 180)
			(size 0.35 0.35)
			(layers "F.Cu" "F.Mask" "F.Paste")
			(net 329 "/FPGA HSIO/Crosslink_B2.D1")
			(pinfunction "PB2D/MIPI_CLKC2_0")
			(pintype "bidirectional")
			(solder_mask_margin -0.025)
			(solder_paste_margin -0.025)
		)
		(pad "H10" smd circle
			(at 2.925 1.625 180)
			(size 0.35 0.35)
			(layers "F.Cu" "F.Mask" "F.Paste")
			(net 131 "/FPGA HSIO/Crosslink_B2.D2")
			(pinfunction "PB2C/MIPI_CLKT2_0")
			(pintype "bidirectional")
			(solder_mask_margin -0.025)
			(solder_paste_margin -0.025)
		)
		(pad "J1" smd circle
			(at -2.925 2.275 180)
			(size 0.35 0.35)
			(layers "F.Cu" "F.Mask" "F.Paste")
			(net 545 "/FPGA GPIO/Crosslink.CLK")
			(pinfunction "PB53/SPI_SCK/MCK/SDA")
			(pintype "bidirectional")
			(solder_mask_margin -0.025)
			(solder_paste_margin -0.025)
		)
	)
)
